(kicad_pcb
	(version 20260206)
	(generator "pcbnew")
	(generator_version "10.0")
	(general
		(thickness 1.6)
		(legacy_teardrops no)
	)
	(paper "A4")
	(title_block
		(title "04192023_DAF0TMB3IC0_F0TG_MB_C_brd_V02_OCP.brd")
		(comment 1 "Grand Teton / footprints 8288-8295 of 8354")
	)
	(layers
		(0 "F.Cu" signal "TOP")
		(4 "In1.Cu" signal "GND")
		(6 "In2.Cu" signal "IN1")
		(8 "In3.Cu" signal "GND1")
		(10 "In4.Cu" signal "IN2")
		(12 "In5.Cu" signal "GND2")
		(14 "In6.Cu" signal "IN3")
		(16 "In7.Cu" signal "GND3")
		(18 "In8.Cu" signal "VCC")
		(20 "In9.Cu" signal "VCC1")
		(22 "In10.Cu" signal "GND4")
		(24 "In11.Cu" signal "IN4")
		(26 "In12.Cu" signal "GND5")
		(28 "In13.Cu" signal "IN5")
		(30 "In14.Cu" signal "GND6")
		(32 "In15.Cu" signal "IN6")
		(34 "In16.Cu" signal "GND7")
		(2 "B.Cu" signal "BOTTOM")
		(9 "F.Adhes" user "F.Adhesive")
		(11 "B.Adhes" user "B.Adhesive")
		(13 "F.Paste" user "Package Geometry/Pastemask Top")
		(15 "B.Paste" user "Package Geometry/Pastemask Bottom")
		(5 "F.SilkS" user "Ref Des/Silkscreen Top")
		(7 "B.SilkS" user "Ref Des/Silkscreen Bottom")
		(1 "F.Mask" user "Board Geometry/Soldermask Top")
		(3 "B.Mask" user "Board Geometry/Soldermask Bottom")
		(17 "Dwgs.User" user "User.Drawings")
		(19 "Cmts.User" user "User.Comments")
		(21 "Eco1.User" user "User.Eco1")
		(23 "Eco2.User" user "User.Eco2")
		(25 "Edge.Cuts" user "Board Geometry/Outline")
		(27 "Margin" user)
		(31 "F.CrtYd" user "Package Geometry/Place Bound Top")
		(29 "B.CrtYd" user "Package Geometry/Place Bound Bottom")
		(35 "F.Fab" user "Ref Des/Assembly Top")
		(33 "B.Fab" user "Ref Des/Assembly Bottom")
	)
	(footprint ""
		(layer "B.Cu")
		(at 144.883886 -408.517344 90)
		(property "Reference" "C6743"
			(at 0 0 90)
			(layer "B.SilkS")
			(hide yes)
			(effects
				(font
					(size 1.27 1.27)
				)
				(justify mirror)
			)
		)
		(property "Value" ""
			(at 0 0 90)
			(layer "B.Fab")
			(effects
				(font
					(size 1.27 1.27)
				)
				(justify mirror)
			)
		)
		(duplicate_pad_numbers_are_jumpers no)
		(fp_line
			(start 0.299974 -0.150114)
			(end -0.299974 -0.150114)
			(stroke
				(width 0.1)
				(type default)
			)
			(layer "B.Fab")
		)
		(fp_line
			(start -0.299974 -0.150114)
			(end -0.299974 0.150114)
			(stroke
				(width 0.1)
				(type default)
			)
			(layer "B.Fab")
		)
		(fp_line
			(start 0.299974 0.150114)
			(end 0.299974 -0.150114)
			(stroke
				(width 0.1)
				(type default)
			)
			(layer "B.Fab")
		)
		(fp_line
			(start -0.299974 0.150114)
			(end 0.299974 0.150114)
			(stroke
				(width 0.1)
				(type default)
			)
			(layer "B.Fab")
		)
		(pad "1" smd rect
			(at 0.2667 0 270)
			(size 0.3048 0.381)
			(layers "B.Cu" "B.Mask" "B.Paste")
			(net "P5E_CPU1_P3_TX_BUF_C_DP<9>")
		)
		(pad "2" smd rect
			(at -0.2667 0 270)
			(size 0.3048 0.381)
			(layers "B.Cu" "B.Mask" "B.Paste")
			(net "P5E_CPU1_P3_TX_BUF_DP<9>")
		)
	)
	(footprint ""
		(layer "B.Cu")
		(at 83.269074 -326.315832 -90)
		(property "Reference" "PC397_2"
			(at 0 0 90)
			(layer "B.SilkS")
			(hide yes)
			(effects
				(font
					(size 1.27 1.27)
				)
				(justify mirror)
			)
		)
		(property "Value" ""
			(at 0 0 90)
			(layer "B.Fab")
			(effects
				(font
					(size 1.27 1.27)
				)
				(justify mirror)
			)
		)
		(duplicate_pad_numbers_are_jumpers no)
		(fp_line
			(start -1.524 0.762)
			(end 1.524 0.762)
			(stroke
				(width 0.1524)
				(type default)
			)
			(layer "B.SilkS")
		)
		(fp_line
			(start 1.524 0.762)
			(end 1.524 -0.762)
			(stroke
				(width 0.1524)
				(type default)
			)
			(layer "B.SilkS")
		)
		(fp_line
			(start -1.524 -0.762)
			(end -1.524 0.762)
			(stroke
				(width 0.1524)
				(type default)
			)
			(layer "B.SilkS")
		)
		(fp_line
			(start 1.524 -0.762)
			(end -1.524 -0.762)
			(stroke
				(width 0.1524)
				(type default)
			)
			(layer "B.SilkS")
		)
		(fp_line
			(start -1.1049 0.724916)
			(end -1.1049 -0.724916)
			(stroke
				(width 0.1)
				(type default)
			)
			(layer "B.Fab")
		)
		(fp_line
			(start 1.1049 0.724916)
			(end -1.1049 0.724916)
			(stroke
				(width 0.1)
				(type default)
			)
			(layer "B.Fab")
		)
		(fp_line
			(start -1.1049 -0.724916)
			(end 1.1049 -0.724916)
			(stroke
				(width 0.1)
				(type default)
			)
			(layer "B.Fab")
		)
		(fp_line
			(start 1.1049 -0.724916)
			(end 1.1049 0.724916)
			(stroke
				(width 0.1)
				(type default)
			)
			(layer "B.Fab")
		)
		(pad "1" smd rect
			(at 0.889 0 270)
			(size 1.016 1.27)
			(layers "B.Cu" "B.Mask" "B.Paste")
			(net "PVDDCR_CPU1_P1")
		)
		(pad "2" smd rect
			(at -0.889 0 270)
			(size 1.016 1.27)
			(layers "B.Cu" "B.Mask" "B.Paste")
			(net "GND")
		)
	)
	(footprint ""
		(layer "B.Cu")
		(at 172.352208 -342.261952 -90)
		(property "Reference" "PC529_1"
			(at 0 0 90)
			(layer "B.SilkS")
			(hide yes)
			(effects
				(font
					(size 1.27 1.27)
				)
				(justify mirror)
			)
		)
		(property "Value" ""
			(at 0 0 90)
			(layer "B.Fab")
			(effects
				(font
					(size 1.27 1.27)
				)
				(justify mirror)
			)
		)
		(duplicate_pad_numbers_are_jumpers no)
		(fp_line
			(start -1.524 0.762)
			(end 1.524 0.762)
			(stroke
				(width 0.1524)
				(type default)
			)
			(layer "B.SilkS")
		)
		(fp_line
			(start 1.524 0.762)
			(end 1.524 -0.762)
			(stroke
				(width 0.1524)
				(type default)
			)
			(layer "B.SilkS")
		)
		(fp_line
			(start -1.524 -0.762)
			(end -1.524 0.762)
			(stroke
				(width 0.1524)
				(type default)
			)
			(layer "B.SilkS")
		)
		(fp_line
			(start 1.524 -0.762)
			(end -1.524 -0.762)
			(stroke
				(width 0.1524)
				(type default)
			)
			(layer "B.SilkS")
		)
		(fp_line
			(start -1.1049 0.724916)
			(end -1.1049 -0.724916)
			(stroke
				(width 0.1)
				(type default)
			)
			(layer "B.Fab")
		)
		(fp_line
			(start 1.1049 0.724916)
			(end -1.1049 0.724916)
			(stroke
				(width 0.1)
				(type default)
			)
			(layer "B.Fab")
		)
		(fp_line
			(start -1.1049 -0.724916)
			(end 1.1049 -0.724916)
			(stroke
				(width 0.1)
				(type default)
			)
			(layer "B.Fab")
		)
		(fp_line
			(start 1.1049 -0.724916)
			(end 1.1049 0.724916)
			(stroke
				(width 0.1)
				(type default)
			)
			(layer "B.Fab")
		)
		(pad "1" smd rect
			(at 0.889 0 270)
			(size 1.016 1.27)
			(layers "B.Cu" "B.Mask" "B.Paste")
			(net "PVDD11_S3_P1")
		)
		(pad "2" smd rect
			(at -0.889 0 270)
			(size 1.016 1.27)
			(layers "B.Cu" "B.Mask" "B.Paste")
			(net "GND")
		)
	)
	(footprint ""
		(layer "B.Cu")
		(at 238.252 -217.678 90)
		(property "Reference" "R1151"
			(at 0 0 90)
			(layer "B.SilkS")
			(hide yes)
			(effects
				(font
					(size 1.27 1.27)
				)
				(justify mirror)
			)
		)
		(property "Value" ""
			(at 0 0 90)
			(layer "B.Fab")
			(effects
				(font
					(size 1.27 1.27)
				)
				(justify mirror)
			)
		)
		(duplicate_pad_numbers_are_jumpers no)
		(fp_line
			(start 0.7874 -0.4064)
			(end -0.7874 -0.4064)
			(stroke
				(width 0.1524)
				(type default)
			)
			(layer "B.SilkS")
		)
		(fp_line
			(start -0.7874 -0.4064)
			(end -0.7874 0.4064)
			(stroke
				(width 0.1524)
				(type default)
			)
			(layer "B.SilkS")
		)
		(fp_line
			(start 0.7874 0.4064)
			(end 0.7874 -0.4064)
			(stroke
				(width 0.1524)
				(type default)
			)
			(layer "B.SilkS")
		)
		(fp_line
			(start -0.7874 0.4064)
			(end 0.7874 0.4064)
			(stroke
				(width 0.1524)
				(type default)
			)
			(layer "B.SilkS")
		)
		(fp_line
			(start 0.67945 -0.305054)
			(end 0.12065 -0.305054)
			(stroke
				(width 0.1)
				(type default)
			)
			(layer "B.Fab")
		)
		(fp_line
			(start 0.12065 -0.305054)
			(end 0.12065 -0.2794)
			(stroke
				(width 0.1)
				(type default)
			)
			(layer "B.Fab")
		)
		(fp_line
			(start -0.12065 -0.3048)
			(end -0.67945 -0.3048)
			(stroke
				(width 0.1)
				(type default)
			)
			(layer "B.Fab")
		)
		(fp_line
			(start -0.67945 -0.3048)
			(end -0.67945 0.3048)
			(stroke
				(width 0.1)
				(type default)
			)
			(layer "B.Fab")
		)
		(fp_line
			(start 0.12065 -0.2794)
			(end -0.12065 -0.2794)
			(stroke
				(width 0.1)
				(type default)
			)
			(layer "B.Fab")
		)
		(fp_line
			(start -0.12065 -0.2794)
			(end -0.12065 -0.3048)
			(stroke
				(width 0.1)
				(type default)
			)
			(layer "B.Fab")
		)
		(fp_line
			(start 0.12065 0.2794)
			(end 0.12065 0.3048)
			(stroke
				(width 0.1)
				(type default)
			)
			(layer "B.Fab")
		)
		(fp_line
			(start -0.120396 0.2794)
			(end 0.12065 0.2794)
			(stroke
				(width 0.1)
				(type default)
			)
			(layer "B.Fab")
		)
		(fp_line
			(start 0.67945 0.3048)
			(end 0.67945 -0.305054)
			(stroke
				(width 0.1)
				(type default)
			)
			(layer "B.Fab")
		)
		(fp_line
			(start 0.12065 0.3048)
			(end 0.67945 0.3048)
			(stroke
				(width 0.1)
				(type default)
			)
			(layer "B.Fab")
		)
		(fp_line
			(start -0.120396 0.3048)
			(end -0.120396 0.2794)
			(stroke
				(width 0.1)
				(type default)
			)
			(layer "B.Fab")
		)
		(fp_line
			(start -0.67945 0.3048)
			(end -0.120396 0.3048)
			(stroke
				(width 0.1)
				(type default)
			)
			(layer "B.Fab")
		)
		(pad "1" smd circle
			(at 0.40005 0 270)
			(size 0 0)
			(layers "B.Cu" "B.Mask" "B.Paste")
			(net "SMB_CPU0_CPU1_APML_BUF1_SCL_R1")
		)
		(pad "2" smd circle
			(at -0.40005 0 270)
			(size 0 0)
			(layers "B.Cu" "B.Mask" "B.Paste")
			(net "SMB_CPU0_CPU1_APML_BUF1_SCL_R2")
		)
	)
	(footprint ""
		(layer "B.Cu")
		(at 133.8453 -390.560052 90)
		(property "Reference" "C486"
			(at 0 0 90)
			(layer "B.SilkS")
			(hide yes)
			(effects
				(font
					(size 1.27 1.27)
				)
				(justify mirror)
			)
		)
		(property "Value" ""
			(at 0 0 90)
			(layer "B.Fab")
			(effects
				(font
					(size 1.27 1.27)
				)
				(justify mirror)
			)
		)
		(duplicate_pad_numbers_are_jumpers no)
		(fp_line
			(start 0.7874 -0.4064)
			(end -0.7874 -0.4064)
			(stroke
				(width 0.1524)
				(type default)
			)
			(layer "B.SilkS")
		)
		(fp_line
			(start -0.7874 -0.4064)
			(end -0.7874 0.4064)
			(stroke
				(width 0.1524)
				(type default)
			)
			(layer "B.SilkS")
		)
		(fp_line
			(start 0.7874 0.4064)
			(end 0.7874 -0.4064)
			(stroke
				(width 0.1524)
				(type default)
			)
			(layer "B.SilkS")
		)
		(fp_line
			(start -0.7874 0.4064)
			(end 0.7874 0.4064)
			(stroke
				(width 0.1524)
				(type default)
			)
			(layer "B.SilkS")
		)
		(fp_line
			(start 0.67945 -0.305054)
			(end 0.12065 -0.305054)
			(stroke
				(width 0.1)
				(type default)
			)
			(layer "B.Fab")
		)
		(fp_line
			(start 0.12065 -0.305054)
			(end 0.12065 -0.2794)
			(stroke
				(width 0.1)
				(type default)
			)
			(layer "B.Fab")
		)
		(fp_line
			(start -0.12065 -0.3048)
			(end -0.67945 -0.3048)
			(stroke
				(width 0.1)
				(type default)
			)
			(layer "B.Fab")
		)
		(fp_line
			(start -0.67945 -0.3048)
			(end -0.67945 0.3048)
			(stroke
				(width 0.1)
				(type default)
			)
			(layer "B.Fab")
		)
		(fp_line
			(start 0.12065 -0.2794)
			(end -0.12065 -0.2794)
			(stroke
				(width 0.1)
				(type default)
			)
			(layer "B.Fab")
		)
		(fp_line
			(start -0.12065 -0.2794)
			(end -0.12065 -0.3048)
			(stroke
				(width 0.1)
				(type default)
			)
			(layer "B.Fab")
		)
		(fp_line
			(start 0.12065 0.2794)
			(end 0.12065 0.3048)
			(stroke
				(width 0.1)
				(type default)
			)
			(layer "B.Fab")
		)
		(fp_line
			(start -0.120396 0.2794)
			(end 0.12065 0.2794)
			(stroke
				(width 0.1)
				(type default)
			)
			(layer "B.Fab")
		)
		(fp_line
			(start 0.67945 0.3048)
			(end 0.67945 -0.305054)
			(stroke
				(width 0.1)
				(type default)
			)
			(layer "B.Fab")
		)
		(fp_line
			(start 0.12065 0.3048)
			(end 0.67945 0.3048)
			(stroke
				(width 0.1)
				(type default)
			)
			(layer "B.Fab")
		)
		(fp_line
			(start -0.120396 0.3048)
			(end -0.120396 0.2794)
			(stroke
				(width 0.1)
				(type default)
			)
			(layer "B.Fab")
		)
		(fp_line
			(start -0.67945 0.3048)
			(end -0.120396 0.3048)
			(stroke
				(width 0.1)
				(type default)
			)
			(layer "B.Fab")
		)
		(pad "1" smd circle
			(at 0.40005 0 270)
			(size 0 0)
			(layers "B.Cu" "B.Mask" "B.Paste")
			(net "P0V9_CPU1_RT3_2A")
		)
		(pad "2" smd circle
			(at -0.40005 0 270)
			(size 0 0)
			(layers "B.Cu" "B.Mask" "B.Paste")
			(net "GND")
		)
	)
	(footprint ""
		(layer "B.Cu")
		(at 410.160216 -177.225452 90)
		(property "Reference" "PC600_2"
			(at 0 0 90)
			(layer "B.SilkS")
			(hide yes)
			(effects
				(font
					(size 1.27 1.27)
				)
				(justify mirror)
			)
		)
		(property "Value" ""
			(at 0 0 90)
			(layer "B.Fab")
			(effects
				(font
					(size 1.27 1.27)
				)
				(justify mirror)
			)
		)
		(duplicate_pad_numbers_are_jumpers no)
		(fp_line
			(start 1.524 -0.762)
			(end -1.524 -0.762)
			(stroke
				(width 0.1524)
				(type default)
			)
			(layer "B.SilkS")
		)
		(fp_line
			(start -1.524 -0.762)
			(end -1.524 0.762)
			(stroke
				(width 0.1524)
				(type default)
			)
			(layer "B.SilkS")
		)
		(fp_line
			(start 1.524 0.762)
			(end 1.524 -0.762)
			(stroke
				(width 0.1524)
				(type default)
			)
			(layer "B.SilkS")
		)
		(fp_line
			(start -1.524 0.762)
			(end 1.524 0.762)
			(stroke
				(width 0.1524)
				(type default)
			)
			(layer "B.SilkS")
		)
		(fp_line
			(start 1.1049 -0.724916)
			(end 1.1049 0.724916)
			(stroke
				(width 0.1)
				(type default)
			)
			(layer "B.Fab")
		)
		(fp_line
			(start -1.1049 -0.724916)
			(end 1.1049 -0.724916)
			(stroke
				(width 0.1)
				(type default)
			)
			(layer "B.Fab")
		)
		(fp_line
			(start 1.1049 0.724916)
			(end -1.1049 0.724916)
			(stroke
				(width 0.1)
				(type default)
			)
			(layer "B.Fab")
		)
		(fp_line
			(start -1.1049 0.724916)
			(end -1.1049 -0.724916)
			(stroke
				(width 0.1)
				(type default)
			)
			(layer "B.Fab")
		)
		(pad "1" smd rect
			(at 0.889 0 90)
			(size 1.016 1.27)
			(layers "B.Cu" "B.Mask" "B.Paste")
			(net "PVDDCR_SOC_P0")
		)
		(pad "2" smd rect
			(at -0.889 0 90)
			(size 1.016 1.27)
			(layers "B.Cu" "B.Mask" "B.Paste")
			(net "GND")
		)
	)
	(footprint ""
		(layer "B.Cu")
		(at 401.337018 -168.721532 -90)
		(property "Reference" "PC595_2"
			(at 0 0 90)
			(layer "B.SilkS")
			(hide yes)
			(effects
				(font
					(size 1.27 1.27)
				)
				(justify mirror)
			)
		)
		(property "Value" ""
			(at 0 0 90)
			(layer "B.Fab")
			(effects
				(font
					(size 1.27 1.27)
				)
				(justify mirror)
			)
		)
		(duplicate_pad_numbers_are_jumpers no)
		(fp_line
			(start -1.524 0.762)
			(end 1.524 0.762)
			(stroke
				(width 0.1524)
				(type default)
			)
			(layer "B.SilkS")
		)
		(fp_line
			(start 1.524 0.762)
			(end 1.524 -0.762)
			(stroke
				(width 0.1524)
				(type default)
			)
			(layer "B.SilkS")
		)
		(fp_line
			(start -1.524 -0.762)
			(end -1.524 0.762)
			(stroke
				(width 0.1524)
				(type default)
			)
			(layer "B.SilkS")
		)
		(fp_line
			(start 1.524 -0.762)
			(end -1.524 -0.762)
			(stroke
				(width 0.1524)
				(type default)
			)
			(layer "B.SilkS")
		)
		(fp_line
			(start -1.1049 0.724916)
			(end -1.1049 -0.724916)
			(stroke
				(width 0.1)
				(type default)
			)
			(layer "B.Fab")
		)
		(fp_line
			(start 1.1049 0.724916)
			(end -1.1049 0.724916)
			(stroke
				(width 0.1)
				(type default)
			)
			(layer "B.Fab")
		)
		(fp_line
			(start -1.1049 -0.724916)
			(end 1.1049 -0.724916)
			(stroke
				(width 0.1)
				(type default)
			)
			(layer "B.Fab")
		)
		(fp_line
			(start 1.1049 -0.724916)
			(end 1.1049 0.724916)
			(stroke
				(width 0.1)
				(type default)
			)
			(layer "B.Fab")
		)
		(pad "1" smd rect
			(at 0.889 0 270)
			(size 1.016 1.27)
			(layers "B.Cu" "B.Mask" "B.Paste")
			(net "SW_P12V_AUX_PVDDCR_SOC_P0_FLT")
		)
		(pad "2" smd rect
			(at -0.889 0 270)
			(size 1.016 1.27)
			(layers "B.Cu" "B.Mask" "B.Paste")
			(net "GND")
		)
	)
	(footprint ""
		(layer "B.Cu")
		(at 10.066782 -406.119584 180)
		(property "Reference" "PR6809"
			(at 0 0 0)
			(layer "B.SilkS")
			(hide yes)
			(effects
				(font
					(size 1.27 1.27)
				)
				(justify mirror)
			)
		)
		(property "Value" ""
			(at 0 0 0)
			(layer "B.Fab")
			(effects
				(font
					(size 1.27 1.27)
				)
				(justify mirror)
			)
		)
		(duplicate_pad_numbers_are_jumpers no)
		(fp_line
			(start 0.7874 0.4064)
			(end 0.7874 -0.4064)
			(stroke
				(width 0.1524)
				(type default)
			)
			(layer "B.SilkS")
		)
		(fp_line
			(start 0.7874 -0.4064)
			(end -0.7874 -0.4064)
			(stroke
				(width 0.1524)
				(type default)
			)
			(layer "B.SilkS")
		)
		(fp_line
			(start -0.7874 0.4064)
			(end 0.7874 0.4064)
			(stroke
				(width 0.1524)
				(type default)
			)
			(layer "B.SilkS")
		)
		(fp_line
			(start -0.7874 -0.4064)
			(end -0.7874 0.4064)
			(stroke
				(width 0.1524)
				(type default)
			)
			(layer "B.SilkS")
		)
		(fp_line
			(start 0.67945 0.3048)
			(end 0.67945 -0.305054)
			(stroke
				(width 0.1)
				(type default)
			)
			(layer "B.Fab")
		)
		(fp_line
			(start 0.67945 -0.305054)
			(end 0.12065 -0.305054)
			(stroke
				(width 0.1)
				(type default)
			)
			(layer "B.Fab")
		)
		(fp_line
			(start 0.12065 0.3048)
			(end 0.67945 0.3048)
			(stroke
				(width 0.1)
				(type default)
			)
			(layer "B.Fab")
		)
		(fp_line
			(start 0.12065 0.2794)
			(end 0.12065 0.3048)
			(stroke
				(width 0.1)
				(type default)
			)
			(layer "B.Fab")
		)
		(fp_line
			(start 0.12065 -0.2794)
			(end -0.12065 -0.2794)
			(stroke
				(width 0.1)
				(type default)
			)
			(layer "B.Fab")
		)
		(fp_line
			(start 0.12065 -0.305054)
			(end 0.12065 -0.2794)
			(stroke
				(width 0.1)
				(type default)
			)
			(layer "B.Fab")
		)
		(fp_line
			(start -0.120396 0.3048)
			(end -0.120396 0.2794)
			(stroke
				(width 0.1)
				(type default)
			)
			(layer "B.Fab")
		)
		(fp_line
			(start -0.120396 0.2794)
			(end 0.12065 0.2794)
			(stroke
				(width 0.1)
				(type default)
			)
			(layer "B.Fab")
		)
		(fp_line
			(start -0.12065 -0.2794)
			(end -0.12065 -0.3048)
			(stroke
				(width 0.1)
				(type default)
			)
			(layer "B.Fab")
		)
		(fp_line
			(start -0.12065 -0.3048)
			(end -0.67945 -0.3048)
			(stroke
				(width 0.1)
				(type default)
			)
			(layer "B.Fab")
		)
		(fp_line
			(start -0.67945 0.3048)
			(end -0.120396 0.3048)
			(stroke
				(width 0.1)
				(type default)
			)
			(layer "B.Fab")
		)
		(fp_line
			(start -0.67945 -0.3048)
			(end -0.67945 0.3048)
			(stroke
				(width 0.1)
				(type default)
			)
			(layer "B.Fab")
		)
		(pad "1" smd circle
			(at 0.40005 0)
			(size 0 0)
			(layers "B.Cu" "B.Mask" "B.Paste")
			(net "P12V_AUX")
		)
		(pad "2" smd circle
			(at -0.40005 0)
			(size 0 0)
			(layers "B.Cu" "B.Mask" "B.Paste")
			(net "P0V9_RETIMER_CPU1_VINSEN")
		)
	)
)
